(kicad_pcb
	(version 20260206)
	(generator "pcbnew")
	(generator_version "10.0")
	(general
		(thickness 1.6)
		(legacy_teardrops no)
	)
	(paper "A4")
	(title_block
		(title "04192023_DAF0TMB3IC0_F0TG_MB_C_brd_V02_OCP.brd")
		(comment 1 "Grand Teton / footprints 3944-3950 of 8354")
	)
	(layers
		(0 "F.Cu" signal "TOP")
		(4 "In1.Cu" signal "GND")
		(6 "In2.Cu" signal "IN1")
		(8 "In3.Cu" signal "GND1")
		(10 "In4.Cu" signal "IN2")
		(12 "In5.Cu" signal "GND2")
		(14 "In6.Cu" signal "IN3")
		(16 "In7.Cu" signal "GND3")
		(18 "In8.Cu" signal "VCC")
		(20 "In9.Cu" signal "VCC1")
		(22 "In10.Cu" signal "GND4")
		(24 "In11.Cu" signal "IN4")
		(26 "In12.Cu" signal "GND5")
		(28 "In13.Cu" signal "IN5")
		(30 "In14.Cu" signal "GND6")
		(32 "In15.Cu" signal "IN6")
		(34 "In16.Cu" signal "GND7")
		(2 "B.Cu" signal "BOTTOM")
		(9 "F.Adhes" user "F.Adhesive")
		(11 "B.Adhes" user "B.Adhesive")
		(13 "F.Paste" user "Package Geometry/Pastemask Top")
		(15 "B.Paste" user "Package Geometry/Pastemask Bottom")
		(5 "F.SilkS" user "Ref Des/Silkscreen Top")
		(7 "B.SilkS" user "Ref Des/Silkscreen Bottom")
		(1 "F.Mask" user "Board Geometry/Soldermask Top")
		(3 "B.Mask" user "Board Geometry/Soldermask Bottom")
		(17 "Dwgs.User" user "User.Drawings")
		(19 "Cmts.User" user "User.Comments")
		(21 "Eco1.User" user "User.Eco1")
		(23 "Eco2.User" user "User.Eco2")
		(25 "Edge.Cuts" user "Board Geometry/Outline")
		(27 "Margin" user)
		(31 "F.CrtYd" user "Package Geometry/Place Bound Top")
		(29 "B.CrtYd" user "Package Geometry/Place Bound Bottom")
		(35 "F.Fab" user "Ref Des/Assembly Top")
		(33 "B.Fab" user "Ref Des/Assembly Bottom")
	)
	(footprint ""
		(layer "F.Cu")
		(at 370.813584 -15.236952 90)
		(property "Reference" "C72"
			(at 0 0 90)
			(layer "F.SilkS")
			(hide yes)
			(effects
				(font
					(size 1.27 1.27)
				)
			)
		)
		(property "Value" ""
			(at 0 0 90)
			(layer "F.Fab")
			(effects
				(font
					(size 1.27 1.27)
				)
			)
		)
		(duplicate_pad_numbers_are_jumpers no)
		(fp_line
			(start 0.7874 -0.4064)
			(end 0.7874 0.4064)
			(stroke
				(width 0.1524)
				(type default)
			)
			(layer "F.SilkS")
		)
		(fp_line
			(start -0.7874 -0.4064)
			(end 0.7874 -0.4064)
			(stroke
				(width 0.1524)
				(type default)
			)
			(layer "F.SilkS")
		)
		(fp_line
			(start 0.7874 0.4064)
			(end -0.7874 0.4064)
			(stroke
				(width 0.1524)
				(type default)
			)
			(layer "F.SilkS")
		)
		(fp_line
			(start -0.7874 0.4064)
			(end -0.7874 -0.4064)
			(stroke
				(width 0.1524)
				(type default)
			)
			(layer "F.SilkS")
		)
		(fp_line
			(start -0.12065 -0.305054)
			(end -0.12065 -0.2794)
			(stroke
				(width 0.1)
				(type default)
			)
			(layer "F.Fab")
		)
		(fp_line
			(start -0.67945 -0.305054)
			(end -0.12065 -0.305054)
			(stroke
				(width 0.1)
				(type default)
			)
			(layer "F.Fab")
		)
		(fp_line
			(start 0.67945 -0.3048)
			(end 0.67945 0.3048)
			(stroke
				(width 0.1)
				(type default)
			)
			(layer "F.Fab")
		)
		(fp_line
			(start 0.12065 -0.3048)
			(end 0.67945 -0.3048)
			(stroke
				(width 0.1)
				(type default)
			)
			(layer "F.Fab")
		)
		(fp_line
			(start 0.12065 -0.2794)
			(end 0.12065 -0.3048)
			(stroke
				(width 0.1)
				(type default)
			)
			(layer "F.Fab")
		)
		(fp_line
			(start -0.12065 -0.2794)
			(end 0.12065 -0.2794)
			(stroke
				(width 0.1)
				(type default)
			)
			(layer "F.Fab")
		)
		(fp_line
			(start 0.120396 0.2794)
			(end -0.12065 0.2794)
			(stroke
				(width 0.1)
				(type default)
			)
			(layer "F.Fab")
		)
		(fp_line
			(start -0.12065 0.2794)
			(end -0.12065 0.3048)
			(stroke
				(width 0.1)
				(type default)
			)
			(layer "F.Fab")
		)
		(fp_line
			(start 0.67945 0.3048)
			(end 0.120396 0.3048)
			(stroke
				(width 0.1)
				(type default)
			)
			(layer "F.Fab")
		)
		(fp_line
			(start 0.120396 0.3048)
			(end 0.120396 0.2794)
			(stroke
				(width 0.1)
				(type default)
			)
			(layer "F.Fab")
		)
		(fp_line
			(start -0.12065 0.3048)
			(end -0.67945 0.3048)
			(stroke
				(width 0.1)
				(type default)
			)
			(layer "F.Fab")
		)
		(fp_line
			(start -0.67945 0.3048)
			(end -0.67945 -0.305054)
			(stroke
				(width 0.1)
				(type default)
			)
			(layer "F.Fab")
		)
		(pad "1" smd circle
			(at -0.40005 0 90)
			(size 0 0)
			(layers "F.Cu" "F.Mask" "F.Paste")
			(net "P3V3_AUX")
		)
		(pad "2" smd circle
			(at 0.40005 0 90)
			(size 0 0)
			(layers "F.Cu" "F.Mask" "F.Paste")
			(net "GND")
		)
	)
	(footprint ""
		(layer "F.Cu")
		(at 107.675934 -256.012442 90)
		(property "Reference" "C2412"
			(at 0 0 90)
			(layer "F.SilkS")
			(hide yes)
			(effects
				(font
					(size 1.27 1.27)
				)
			)
		)
		(property "Value" ""
			(at 0 0 90)
			(layer "F.Fab")
			(effects
				(font
					(size 1.27 1.27)
				)
			)
		)
		(duplicate_pad_numbers_are_jumpers no)
		(fp_line
			(start 0.7874 -0.4064)
			(end 0.7874 0.4064)
			(stroke
				(width 0.1524)
				(type default)
			)
			(layer "F.SilkS")
		)
		(fp_line
			(start -0.7874 -0.4064)
			(end 0.7874 -0.4064)
			(stroke
				(width 0.1524)
				(type default)
			)
			(layer "F.SilkS")
		)
		(fp_line
			(start 0.7874 0.4064)
			(end -0.7874 0.4064)
			(stroke
				(width 0.1524)
				(type default)
			)
			(layer "F.SilkS")
		)
		(fp_line
			(start -0.7874 0.4064)
			(end -0.7874 -0.4064)
			(stroke
				(width 0.1524)
				(type default)
			)
			(layer "F.SilkS")
		)
		(fp_line
			(start -0.12065 -0.305054)
			(end -0.12065 -0.2794)
			(stroke
				(width 0.1)
				(type default)
			)
			(layer "F.Fab")
		)
		(fp_line
			(start -0.67945 -0.305054)
			(end -0.12065 -0.305054)
			(stroke
				(width 0.1)
				(type default)
			)
			(layer "F.Fab")
		)
		(fp_line
			(start 0.67945 -0.3048)
			(end 0.67945 0.3048)
			(stroke
				(width 0.1)
				(type default)
			)
			(layer "F.Fab")
		)
		(fp_line
			(start 0.12065 -0.3048)
			(end 0.67945 -0.3048)
			(stroke
				(width 0.1)
				(type default)
			)
			(layer "F.Fab")
		)
		(fp_line
			(start 0.12065 -0.2794)
			(end 0.12065 -0.3048)
			(stroke
				(width 0.1)
				(type default)
			)
			(layer "F.Fab")
		)
		(fp_line
			(start -0.12065 -0.2794)
			(end 0.12065 -0.2794)
			(stroke
				(width 0.1)
				(type default)
			)
			(layer "F.Fab")
		)
		(fp_line
			(start 0.120396 0.2794)
			(end -0.12065 0.2794)
			(stroke
				(width 0.1)
				(type default)
			)
			(layer "F.Fab")
		)
		(fp_line
			(start -0.12065 0.2794)
			(end -0.12065 0.3048)
			(stroke
				(width 0.1)
				(type default)
			)
			(layer "F.Fab")
		)
		(fp_line
			(start 0.67945 0.3048)
			(end 0.120396 0.3048)
			(stroke
				(width 0.1)
				(type default)
			)
			(layer "F.Fab")
		)
		(fp_line
			(start 0.120396 0.3048)
			(end 0.120396 0.2794)
			(stroke
				(width 0.1)
				(type default)
			)
			(layer "F.Fab")
		)
		(fp_line
			(start -0.12065 0.3048)
			(end -0.67945 0.3048)
			(stroke
				(width 0.1)
				(type default)
			)
			(layer "F.Fab")
		)
		(fp_line
			(start -0.67945 0.3048)
			(end -0.67945 -0.305054)
			(stroke
				(width 0.1)
				(type default)
			)
			(layer "F.Fab")
		)
		(pad "1" smd circle
			(at -0.40005 0 90)
			(size 0 0)
			(layers "F.Cu" "F.Mask" "F.Paste")
			(net "PVDDCR_SOC_P1")
		)
		(pad "2" smd circle
			(at 0.40005 0 90)
			(size 0 0)
			(layers "F.Cu" "F.Mask" "F.Paste")
			(net "GND")
		)
	)
	(footprint ""
		(layer "F.Cu")
		(at 326.330056 -23.826216 -90)
		(property "Reference" "R5053"
			(at 0 0 270)
			(layer "F.SilkS")
			(hide yes)
			(effects
				(font
					(size 1.27 1.27)
				)
			)
		)
		(property "Value" ""
			(at 0 0 270)
			(layer "F.Fab")
			(effects
				(font
					(size 1.27 1.27)
				)
			)
		)
		(duplicate_pad_numbers_are_jumpers no)
		(fp_line
			(start -0.7874 0.4064)
			(end -0.7874 -0.4064)
			(stroke
				(width 0.1524)
				(type default)
			)
			(layer "F.SilkS")
		)
		(fp_line
			(start 0.7874 0.4064)
			(end -0.7874 0.4064)
			(stroke
				(width 0.1524)
				(type default)
			)
			(layer "F.SilkS")
		)
		(fp_line
			(start -0.7874 -0.4064)
			(end 0.7874 -0.4064)
			(stroke
				(width 0.1524)
				(type default)
			)
			(layer "F.SilkS")
		)
		(fp_line
			(start 0.7874 -0.4064)
			(end 0.7874 0.4064)
			(stroke
				(width 0.1524)
				(type default)
			)
			(layer "F.SilkS")
		)
		(fp_line
			(start -0.67945 0.3048)
			(end -0.67945 -0.305054)
			(stroke
				(width 0.1)
				(type default)
			)
			(layer "F.Fab")
		)
		(fp_line
			(start -0.12065 0.3048)
			(end -0.67945 0.3048)
			(stroke
				(width 0.1)
				(type default)
			)
			(layer "F.Fab")
		)
		(fp_line
			(start 0.120396 0.3048)
			(end 0.120396 0.2794)
			(stroke
				(width 0.1)
				(type default)
			)
			(layer "F.Fab")
		)
		(fp_line
			(start 0.67945 0.3048)
			(end 0.120396 0.3048)
			(stroke
				(width 0.1)
				(type default)
			)
			(layer "F.Fab")
		)
		(fp_line
			(start -0.12065 0.2794)
			(end -0.12065 0.3048)
			(stroke
				(width 0.1)
				(type default)
			)
			(layer "F.Fab")
		)
		(fp_line
			(start 0.120396 0.2794)
			(end -0.12065 0.2794)
			(stroke
				(width 0.1)
				(type default)
			)
			(layer "F.Fab")
		)
		(fp_line
			(start -0.12065 -0.2794)
			(end 0.12065 -0.2794)
			(stroke
				(width 0.1)
				(type default)
			)
			(layer "F.Fab")
		)
		(fp_line
			(start 0.12065 -0.2794)
			(end 0.12065 -0.3048)
			(stroke
				(width 0.1)
				(type default)
			)
			(layer "F.Fab")
		)
		(fp_line
			(start 0.12065 -0.3048)
			(end 0.67945 -0.3048)
			(stroke
				(width 0.1)
				(type default)
			)
			(layer "F.Fab")
		)
		(fp_line
			(start 0.67945 -0.3048)
			(end 0.67945 0.3048)
			(stroke
				(width 0.1)
				(type default)
			)
			(layer "F.Fab")
		)
		(fp_line
			(start -0.67945 -0.305054)
			(end -0.12065 -0.305054)
			(stroke
				(width 0.1)
				(type default)
			)
			(layer "F.Fab")
		)
		(fp_line
			(start -0.12065 -0.305054)
			(end -0.12065 -0.2794)
			(stroke
				(width 0.1)
				(type default)
			)
			(layer "F.Fab")
		)
		(pad "1" smd circle
			(at -0.40005 0 270)
			(size 0 0)
			(layers "F.Cu" "F.Mask" "F.Paste")
			(net "P1V5_BAT_OUT")
		)
		(pad "2" smd circle
			(at 0.40005 0 270)
			(size 0 0)
			(layers "F.Cu" "F.Mask" "F.Paste")
			(net "P1V5_BAT_OUT_R")
		)
	)
	(footprint ""
		(layer "F.Cu")
		(at 100.285296 -412.931102 90)
		(property "Reference" "R4213"
			(at 0 0 90)
			(layer "F.SilkS")
			(hide yes)
			(effects
				(font
					(size 1.27 1.27)
				)
			)
		)
		(property "Value" ""
			(at 0 0 90)
			(layer "F.Fab")
			(effects
				(font
					(size 1.27 1.27)
				)
			)
		)
		(duplicate_pad_numbers_are_jumpers no)
		(fp_line
			(start 0.7874 -0.4064)
			(end 0.7874 0.4064)
			(stroke
				(width 0.1524)
				(type default)
			)
			(layer "F.SilkS")
		)
		(fp_line
			(start -0.7874 -0.4064)
			(end 0.7874 -0.4064)
			(stroke
				(width 0.1524)
				(type default)
			)
			(layer "F.SilkS")
		)
		(fp_line
			(start 0.7874 0.4064)
			(end -0.7874 0.4064)
			(stroke
				(width 0.1524)
				(type default)
			)
			(layer "F.SilkS")
		)
		(fp_line
			(start -0.7874 0.4064)
			(end -0.7874 -0.4064)
			(stroke
				(width 0.1524)
				(type default)
			)
			(layer "F.SilkS")
		)
		(fp_line
			(start -0.12065 -0.305054)
			(end -0.12065 -0.2794)
			(stroke
				(width 0.1)
				(type default)
			)
			(layer "F.Fab")
		)
		(fp_line
			(start -0.67945 -0.305054)
			(end -0.12065 -0.305054)
			(stroke
				(width 0.1)
				(type default)
			)
			(layer "F.Fab")
		)
		(fp_line
			(start 0.67945 -0.3048)
			(end 0.67945 0.3048)
			(stroke
				(width 0.1)
				(type default)
			)
			(layer "F.Fab")
		)
		(fp_line
			(start 0.12065 -0.3048)
			(end 0.67945 -0.3048)
			(stroke
				(width 0.1)
				(type default)
			)
			(layer "F.Fab")
		)
		(fp_line
			(start 0.12065 -0.2794)
			(end 0.12065 -0.3048)
			(stroke
				(width 0.1)
				(type default)
			)
			(layer "F.Fab")
		)
		(fp_line
			(start -0.12065 -0.2794)
			(end 0.12065 -0.2794)
			(stroke
				(width 0.1)
				(type default)
			)
			(layer "F.Fab")
		)
		(fp_line
			(start 0.120396 0.2794)
			(end -0.12065 0.2794)
			(stroke
				(width 0.1)
				(type default)
			)
			(layer "F.Fab")
		)
		(fp_line
			(start -0.12065 0.2794)
			(end -0.12065 0.3048)
			(stroke
				(width 0.1)
				(type default)
			)
			(layer "F.Fab")
		)
		(fp_line
			(start 0.67945 0.3048)
			(end 0.120396 0.3048)
			(stroke
				(width 0.1)
				(type default)
			)
			(layer "F.Fab")
		)
		(fp_line
			(start 0.120396 0.3048)
			(end 0.120396 0.2794)
			(stroke
				(width 0.1)
				(type default)
			)
			(layer "F.Fab")
		)
		(fp_line
			(start -0.12065 0.3048)
			(end -0.67945 0.3048)
			(stroke
				(width 0.1)
				(type default)
			)
			(layer "F.Fab")
		)
		(fp_line
			(start -0.67945 0.3048)
			(end -0.67945 -0.305054)
			(stroke
				(width 0.1)
				(type default)
			)
			(layer "F.Fab")
		)
		(pad "1" smd circle
			(at -0.40005 0 90)
			(size 0 0)
			(layers "F.Cu" "F.Mask" "F.Paste")
			(net "FM_THERMAL_ALERT_N")
		)
		(pad "2" smd circle
			(at 0.40005 0 90)
			(size 0 0)
			(layers "F.Cu" "F.Mask" "F.Paste")
			(net "FM_LM75_2_ALERT_N")
		)
	)
	(footprint ""
		(layer "F.Cu")
		(at 169.418 -135.509 180)
		(property "Reference" "R479"
			(at 0 0 180)
			(layer "F.SilkS")
			(hide yes)
			(effects
				(font
					(size 1.27 1.27)
				)
			)
		)
		(property "Value" ""
			(at 0 0 180)
			(layer "F.Fab")
			(effects
				(font
					(size 1.27 1.27)
				)
			)
		)
		(duplicate_pad_numbers_are_jumpers no)
		(fp_line
			(start 0.7874 0.4064)
			(end -0.7874 0.4064)
			(stroke
				(width 0.1524)
				(type default)
			)
			(layer "F.SilkS")
		)
		(fp_line
			(start 0.7874 -0.4064)
			(end 0.7874 0.4064)
			(stroke
				(width 0.1524)
				(type default)
			)
			(layer "F.SilkS")
		)
		(fp_line
			(start -0.7874 0.4064)
			(end -0.7874 -0.4064)
			(stroke
				(width 0.1524)
				(type default)
			)
			(layer "F.SilkS")
		)
		(fp_line
			(start -0.7874 -0.4064)
			(end 0.7874 -0.4064)
			(stroke
				(width 0.1524)
				(type default)
			)
			(layer "F.SilkS")
		)
		(fp_line
			(start 0.67945 0.3048)
			(end 0.120396 0.3048)
			(stroke
				(width 0.1)
				(type default)
			)
			(layer "F.Fab")
		)
		(fp_line
			(start 0.67945 -0.3048)
			(end 0.67945 0.3048)
			(stroke
				(width 0.1)
				(type default)
			)
			(layer "F.Fab")
		)
		(fp_line
			(start 0.12065 -0.2794)
			(end 0.12065 -0.3048)
			(stroke
				(width 0.1)
				(type default)
			)
			(layer "F.Fab")
		)
		(fp_line
			(start 0.12065 -0.3048)
			(end 0.67945 -0.3048)
			(stroke
				(width 0.1)
				(type default)
			)
			(layer "F.Fab")
		)
		(fp_line
			(start 0.120396 0.3048)
			(end 0.120396 0.2794)
			(stroke
				(width 0.1)
				(type default)
			)
			(layer "F.Fab")
		)
		(fp_line
			(start 0.120396 0.2794)
			(end -0.12065 0.2794)
			(stroke
				(width 0.1)
				(type default)
			)
			(layer "F.Fab")
		)
		(fp_line
			(start -0.12065 0.3048)
			(end -0.67945 0.3048)
			(stroke
				(width 0.1)
				(type default)
			)
			(layer "F.Fab")
		)
		(fp_line
			(start -0.12065 0.2794)
			(end -0.12065 0.3048)
			(stroke
				(width 0.1)
				(type default)
			)
			(layer "F.Fab")
		)
		(fp_line
			(start -0.12065 -0.2794)
			(end 0.12065 -0.2794)
			(stroke
				(width 0.1)
				(type default)
			)
			(layer "F.Fab")
		)
		(fp_line
			(start -0.12065 -0.305054)
			(end -0.12065 -0.2794)
			(stroke
				(width 0.1)
				(type default)
			)
			(layer "F.Fab")
		)
		(fp_line
			(start -0.67945 0.3048)
			(end -0.67945 -0.305054)
			(stroke
				(width 0.1)
				(type default)
			)
			(layer "F.Fab")
		)
		(fp_line
			(start -0.67945 -0.305054)
			(end -0.12065 -0.305054)
			(stroke
				(width 0.1)
				(type default)
			)
			(layer "F.Fab")
		)
		(pad "1" smd circle
			(at -0.40005 0 180)
			(size 0 0)
			(layers "F.Cu" "F.Mask" "F.Paste")
			(net "P5V")
		)
		(pad "2" smd circle
			(at 0.40005 0 180)
			(size 0 0)
			(layers "F.Cu" "F.Mask" "F.Paste")
			(net "PWRGD_P5V_R")
		)
	)
	(footprint ""
		(layer "F.Cu")
		(at 411.44444 -383.88163 -90)
		(property "Reference" "C854"
			(at 0 0 270)
			(layer "F.SilkS")
			(hide yes)
			(effects
				(font
					(size 1.27 1.27)
				)
			)
		)
		(property "Value" ""
			(at 0 0 270)
			(layer "F.Fab")
			(effects
				(font
					(size 1.27 1.27)
				)
			)
		)
		(duplicate_pad_numbers_are_jumpers no)
		(fp_line
			(start -0.299974 0.150114)
			(end -0.299974 -0.150114)
			(stroke
				(width 0.1)
				(type default)
			)
			(layer "F.Fab")
		)
		(fp_line
			(start 0.299974 0.150114)
			(end -0.299974 0.150114)
			(stroke
				(width 0.1)
				(type default)
			)
			(layer "F.Fab")
		)
		(fp_line
			(start -0.299974 -0.150114)
			(end 0.299974 -0.150114)
			(stroke
				(width 0.1)
				(type default)
			)
			(layer "F.Fab")
		)
		(fp_line
			(start 0.299974 -0.150114)
			(end 0.299974 0.150114)
			(stroke
				(width 0.1)
				(type default)
			)
			(layer "F.Fab")
		)
		(pad "1" smd rect
			(at -0.2667 0 270)
			(size 0.3048 0.381)
			(layers "F.Cu" "F.Mask" "F.Paste")
			(net "P5E_CPU0_P2_TX_C_DN<7>")
		)
		(pad "2" smd rect
			(at 0.2667 0 270)
			(size 0.3048 0.381)
			(layers "F.Cu" "F.Mask" "F.Paste")
			(net "P5E_CPU0_P2_TX_DN<7>")
		)
	)
	(footprint ""
		(layer "F.Cu")
		(at 353.900232 -261.255002)
		(property "Reference" "C2149"
			(at 0 0 0)
			(layer "F.SilkS")
			(hide yes)
			(effects
				(font
					(size 1.27 1.27)
				)
			)
		)
		(property "Value" ""
			(at 0 0 0)
			(layer "F.Fab")
			(effects
				(font
					(size 1.27 1.27)
				)
			)
		)
		(duplicate_pad_numbers_are_jumpers no)
		(fp_line
			(start -0.7874 -0.4064)
			(end 0.7874 -0.4064)
			(stroke
				(width 0.1524)
				(type default)
			)
			(layer "F.SilkS")
		)
		(fp_line
			(start -0.7874 0.4064)
			(end -0.7874 -0.4064)
			(stroke
				(width 0.1524)
				(type default)
			)
			(layer "F.SilkS")
		)
		(fp_line
			(start 0.7874 -0.4064)
			(end 0.7874 0.4064)
			(stroke
				(width 0.1524)
				(type default)
			)
			(layer "F.SilkS")
		)
		(fp_line
			(start 0.7874 0.4064)
			(end -0.7874 0.4064)
			(stroke
				(width 0.1524)
				(type default)
			)
			(layer "F.SilkS")
		)
		(fp_line
			(start -0.67945 -0.305054)
			(end -0.12065 -0.305054)
			(stroke
				(width 0.1)
				(type default)
			)
			(layer "F.Fab")
		)
		(fp_line
			(start -0.67945 0.3048)
			(end -0.67945 -0.305054)
			(stroke
				(width 0.1)
				(type default)
			)
			(layer "F.Fab")
		)
		(fp_line
			(start -0.12065 -0.305054)
			(end -0.12065 -0.2794)
			(stroke
				(width 0.1)
				(type default)
			)
			(layer "F.Fab")
		)
		(fp_line
			(start -0.12065 -0.2794)
			(end 0.12065 -0.2794)
			(stroke
				(width 0.1)
				(type default)
			)
			(layer "F.Fab")
		)
		(fp_line
			(start -0.12065 0.2794)
			(end -0.12065 0.3048)
			(stroke
				(width 0.1)
				(type default)
			)
			(layer "F.Fab")
		)
		(fp_line
			(start -0.12065 0.3048)
			(end -0.67945 0.3048)
			(stroke
				(width 0.1)
				(type default)
			)
			(layer "F.Fab")
		)
		(fp_line
			(start 0.120396 0.2794)
			(end -0.12065 0.2794)
			(stroke
				(width 0.1)
				(type default)
			)
			(layer "F.Fab")
		)
		(fp_line
			(start 0.120396 0.3048)
			(end 0.120396 0.2794)
			(stroke
				(width 0.1)
				(type default)
			)
			(layer "F.Fab")
		)
		(fp_line
			(start 0.12065 -0.3048)
			(end 0.67945 -0.3048)
			(stroke
				(width 0.1)
				(type default)
			)
			(layer "F.Fab")
		)
		(fp_line
			(start 0.12065 -0.2794)
			(end 0.12065 -0.3048)
			(stroke
				(width 0.1)
				(type default)
			)
			(layer "F.Fab")
		)
		(fp_line
			(start 0.67945 -0.3048)
			(end 0.67945 0.3048)
			(stroke
				(width 0.1)
				(type default)
			)
			(layer "F.Fab")
		)
		(fp_line
			(start 0.67945 0.3048)
			(end 0.120396 0.3048)
			(stroke
				(width 0.1)
				(type default)
			)
			(layer "F.Fab")
		)
		(pad "1" smd circle
			(at -0.40005 0)
			(size 0 0)
			(layers "F.Cu" "F.Mask" "F.Paste")
			(net "PVDDIO_P0")
		)
		(pad "2" smd circle
			(at 0.40005 0)
			(size 0 0)
			(layers "F.Cu" "F.Mask" "F.Paste")
			(net "GND")
		)
	)
)
